FILE_TYPE = CONNECTIVITY;
{Allegro Design Entry HDL 17.2-2016 S081 (4005846) 1/11/2022}
"PAGE_NUMBER" = 262;
0"NC";
1"P5V\g";
2"PVCCFA_EHV_CPU0_VDD1\g";
3"P3V3\g";
4"PVCCFA_EHV_CPU0\g";
5"SW_P12V_PVCCINFAON_CPU0_FLT\g";
6"GND\g";
7"GND\g";
8"GND\g";
9"GND\g";
10"GND\g";
11"GND\g";
12"PVCCFA_EHV_CPU0_BTSEN";
13"SW_PVCCFA_EHV_CPU0_SW1";
14"PVCCFA_EHV_CPU0_VDD1";
15"PVCCFA_EHV_CPU0_PVCC";
16"SW_PVCCFA_EHV_CPU0_BOOT1_R";
17"SW_PVCCFA_EHV_CPU0_BOOT1"CDS_PHYS_NET_NAME"SW_PVCCFA_EHV_CPU0_BOOT1";
18"PVCCFA_EHV_CPU0_FAULT";
19"PVCCFA_EHV_CPU0_NC1";
20"SW_PVCCFA_EHV_CPU0_BOOTR1"CDS_PHYS_NET_NAME"SW_PVCCFA_EHV_CPU0_BOOTR1";
21"PVCCFA_EHV_CPU0_BPWM1";
22"PVCCFA_EHV_CPU0_BCSP1";
23"PVCCFA_EHV_CPU0_NC2";
24"PVCCINFAON_CPU0_VREF"CDS_PHYS_NET_NAME"PVCCINFAON_CPU0_VREF";
25"PVCCFA_EHV_CPU0_LSET1";
%"UNIVERSAL_GND"
"1","(-10275,2750)","0","logical_power","I1";
;
HDL_POWER"GND"
CDS_LIB"logical_power";
"A"6;
%"Q_CAP"
"2","(-9500,3350)","0","pure_quanta","I10";
;
PART_NUMBER"CH4104K1B00"
TOLERANCE"10%"
PACK_TYPE"0402"
MATERIAL"X7R"
VOLTAGE"25V"
VALUE"0.1UF"
LOCATION"PC1348"
CDS_LIB"pure_quanta"
$SEC"1"
CDS_SEC"1";
"A"
$PN"1"7;
"B"
$PN"2"24;
%"UNIVERSAL_GND"
"1","(-9600,3750)","0","logical_power","I11";
;
HDL_POWER"GND"
CDS_LIB"logical_power";
"A"8;
%"Q_CAP"
"1","(-9600,4000)","0","pure_quanta","I12";
;
PART_NUMBER"CH5222KEB01"
VALUE"2.2UF"
PACK_TYPE"C0402"
MATERIAL"X6S"
TOLERANCE"10%"
VOLTAGE"10V"
LOCATION"PC175"
CDS_LIB"pure_quanta"
LOCATION"PC175"
$SEC"1"
CDS_SEC"1";
"B"
$PN"2"8;
"A"
$PN"1"14;
%"Q_RES"
"2","(-9075,3950)","0","pure_quanta","I13";
;
PART_NUMBER"CS00002JB13"
PACK_TYPE"0402LF"
WATTAGE"1/16W"
MATERIAL"EMPTY"
TOLERANCE"5%"
VALUE"0"
LOCATION"PR4227"
CDS_LIB"pure_quanta"
$SEC"1"
CDS_SEC"1";
"A"
$PN"1"14;
"B"
$PN"2"23;
%"RAA2213404GNPHB0"
"1","(-8100,3575)","0","pure_quanta","I14";
;
PART_NUMBER"AL221340002"
PART_TYPE"SMLF"
VALUE"RAA2213404GNP#HB0"
MATERIAL"IC"
LOCATION"PU42"
CDS_LIB"pure_quanta"
CDS_LMAN_SYM_OUTLINE"-275,675,275,-675"
NEEDS_NO_SIZE"TRUE"
$SEC"1"
CDS_SEC"1";
"LGCTRL"
$PN"3"19;
"GL1"
$PN"5"25;
"NC1"
$PN"22"23;
"GND3"
$PN"26"9;
"FAULT# \B"
$PN"2"18;
"SW"
$PN"8_12"13;
"GL2"
$PN"27"0;
"GND1"
$PN"6_7-13_15-29"9;
"IMON"
$PN"25"22;
"TMON"
$PN"1"12;
"VCC"
$PN"4"14;
"PHASE"
$PN"19"20;
"VIN"
$PN"16_18-28"5;
"BOOT"
$PN"20"17;
"GND2"
$PN"23"9;
"REFIN"
$PN"24"24;
"PWM"
$PN"21"21;
%"Q_RES"
"1","(-6725,3050)","0","pure_quanta","I15";
;
PART_NUMBER"CS00002JB13"
WATTAGE"1/16W"
MATERIAL"EMPTY"
PACK_TYPE"0402LF"
VALUE"0"
TOLERANCE"5%"
LOCATION"PR4228"
CDS_LIB"pure_quanta"
$SEC"1"
CDS_SEC"1";
"B"
$PN"2"9;
"A"
$PN"1"18;
%"Q_RES"
"1","(-6525,3250)","0","pure_quanta","I16";
;
PART_NUMBER"CS00002JB13"
WATTAGE"1/16W"
TOLERANCE"5%"
VALUE"0"
MATERIAL"CHIP"
PACK_TYPE"0402LF"
LOCATION"PR1779"
CDS_LIB"pure_quanta"
$SEC"1"
CDS_SEC"1";
"B"
$PN"2"2;
"A"
$PN"1"19;
%"Q_RES"
"1","(-6750,4000)","0","pure_quanta","I17";
;
PART_NUMBER"CS-3302FB01"
PACK_TYPE"0402LF"
MATERIAL"CHIP"
WATTAGE"1/16W"
TOLERANCE"1%"
VALUE"3.3"
LOCATION"PR1778"
CDS_LIB"pure_quanta"
$SEC"1"
CDS_SEC"1";
"B"
$PN"2"16;
"A"
$PN"1"17;
%"UNIVERSAL_GND"
"1","(-6100,2825)","0","logical_power","I18";
;
HDL_POWER"GND"
CDS_LIB"logical_power";
"A"9;
%"VCC15"
"1","(-6100,3400)","0","logical_power","I19";
;
HDL_POWER"PVCCFA_EHV_CPU0_VDD1"
CDS_LIB"logical_power";
"A"2;
%"Q_RES"
"2","(-10275,2975)","2","pure_quanta","I2";
;
PART_NUMBER"CS28872FB01"
PACK_TYPE"0402LF"
VALUE"8.87K"
TOLERANCE"1%"
MATERIAL"EMPTY"
WATTAGE"1/16W"
LOCATION"PR1709"
CDS_LIB"pure_quanta"
$SEC"1"
CDS_SEC"1";
"A"
$PN"1"25;
"B"
$PN"2"6;
%"Q_CAP"
"1","(-5950,3825)","2","pure_quanta","I20";
;
PART_NUMBER"CH4106K1B01"
MATERIAL"X7R"
PACK_TYPE"C0402"
VALUE"100NF"
VOLTAGE"50V"
TOLERANCE"10%"
LOCATION"PC178"
CDS_LIB"pure_quanta"
$SEC"1"
CDS_SEC"1";
"B"
$PN"2"20;
"A"
$PN"1"16;
%"Q_RES"
"2","(-9600,4400)","0","pure_quanta","I21";
;
PART_NUMBER"CS-2202FB01"
WATTAGE"1/16W"
MATERIAL"CHIP"
PACK_TYPE"0402LF"
VALUE"2.2"
TOLERANCE"1%"
LOCATION"PR97"
CDS_LIB"pure_quanta"
LOCATION"PR97"
$SEC"1"
CDS_SEC"1";
"A"
$PN"1"15;
"B"
$PN"2"14;
%"Q_RES"
"2","(-9225,5025)","0","pure_quanta","I22";
;
PART_NUMBER"CS00002JB13"
PACK_TYPE"0402LF"
VALUE"0"
TOLERANCE"5%"
MATERIAL"EMPTY"
WATTAGE"1/16W"
LOCATION"PR443"
CDS_LIB"pure_quanta"
$SEC"1"
CDS_SEC"1";
"A"
$PN"1"3;
"B"
$PN"2"15;
%"VCC15"
"1","(-9225,5250)","0","logical_power","I23";
;
HDL_POWER"P3V3"
CDS_LIB"logical_power";
"A"3;
%"Q_CAP"
"1","(-7275,4450)","0","pure_quanta","I24";
;
PART_NUMBER"TMP_QCH2336K1B12"
TOLERANCE"10%"
VOLTAGE"50V"
VALUE"3300PF"
PACK_TYPE"0402"
MATERIAL"X7R"
LOCATION"PC176"
CDS_LIB"pure_quanta"
LOCATION"PC176"
$SEC"1"
CDS_SEC"1";
"B"
$PN"2"10;
"A"
$PN"1"5;
%"Q_CAP"
"1","(-6875,4450)","0","pure_quanta","I25";
;
PART_NUMBER"CH5103KEB01"
VOLTAGE"16V"
PACK_TYPE"C0402"
VALUE"1UF"
MATERIAL"X6S"
TOLERANCE"10%"
LOCATION"PC177"
CDS_LIB"pure_quanta"
LOCATION"PC177"
$SEC"1"
CDS_SEC"1";
"B"
$PN"2"10;
"A"
$PN"1"5;
%"Q_CAP"
"1","(-6475,4450)","0","pure_quanta","I26";
;
PART_NUMBER"CH6223MEA01"
TOLERANCE"20%"
VALUE"22UF"
PACK_TYPE"C0805"
VOLTAGE"16V"
MATERIAL"X6S"
LOCATION"PC179"
CDS_LIB"pure_quanta"
LOCATION"PC179"
$SEC"1"
CDS_SEC"1";
"B"
$PN"2"10;
"A"
$PN"1"5;
%"Q_CAP"
"1","(-6075,4450)","0","pure_quanta","I27";
;
PART_NUMBER"CH6223MEA01"
TOLERANCE"20%"
VALUE"22UF"
PACK_TYPE"C0805"
VOLTAGE"16V"
MATERIAL"X6S"
LOCATION"PC180"
CDS_LIB"pure_quanta"
LOCATION"PC180"
$SEC"1"
CDS_SEC"1";
"B"
$PN"2"10;
"A"
$PN"1"5;
%"Q_CAP"
"1","(-5200,3350)","0","pure_quanta","I28";
;
PART_NUMBER"CH4106K1B01"
VALUE"100NF"
VOLTAGE"50V"
PACK_TYPE"C0402"
TOLERANCE"10%"
MATERIAL"X7R"
LOCATION"PC181"
CDS_LIB"pure_quanta"
LOCATION"PC181"
$SEC"1"
CDS_SEC"1";
"B"
$PN"2"11;
"A"
$PN"1"4;
%"Q_INDUCTOR"
"1","(-5400,3575)","0","pure_quanta","I29";
;
PART_NUMBER"CV+30Y0KZ05"
MATERIAL"IND"
VALUE"300NH/33A"
PACK_TYPE"SMLF"
LOCATION"PL3"
NEEDS_NO_SIZE"TRUE"
CDS_LIB"pure_quanta"
$SEC"1"
CDS_SEC"1";
"1"
$PN"1"13;
"2"
$PN"2"4;
%"UNIVERSAL_GND"
"1","(-5475,4025)","0","logical_power","I30";
;
HDL_POWER"GND"
CDS_LIB"logical_power";
"A"10;
%"Q_CAP"
"1","(-4800,3350)","0","pure_quanta","I31";
;
PART_NUMBER"CH622KMEA03"
TOLERANCE"20%"
VOLTAGE"4V"
PACK_TYPE"C0805"
MATERIAL"X6S"
VALUE"22UF"
LOCATION"PC184"
CDS_LIB"pure_quanta"
LOCATION"PC184"
$SEC"1"
CDS_SEC"1";
"B"
$PN"2"11;
"A"
$PN"1"4;
%"Q_CAP"
"1","(-4375,3350)","0","pure_quanta","I32";
;
PART_NUMBER"CH622KMEA03"
TOLERANCE"20%"
VOLTAGE"4V"
VALUE"22UF"
PACK_TYPE"C0805"
MATERIAL"X6S"
LOCATION"PC186"
CDS_LIB"pure_quanta"
LOCATION"PC186"
$SEC"1"
CDS_SEC"1";
"B"
$PN"2"11;
"A"
$PN"1"4;
%"Q_CAPP"
"1","(-3925,3350)","0","pure_quanta","I33";
;
PART_NUMBER"CC7560JMD16"
PACK_TYPE"THLF"
VALUE"560UF"
TOLERANCE"20%"
MATERIAL"OSCON"
VOLTAGE"2.5V"
LOCATION"PC2180"
CDS_LIB"pure_quanta"
$SEC"1"
CDS_SEC"1";
"A"
$PN"1"4;
"B"
$PN"2"11;
%"Q_CAPP"
"1","(-3525,3350)","0","pure_quanta","I34";
;
PART_NUMBER"CH733LY8802"
VOLTAGE"2.5V"
TOLERANCE"+10/-35%"
MATERIAL"SPCAP"
PACK_TYPE"SMLF"
VALUE"330UF"
LOCATION"PC1900"
CDS_LIB"pure_quanta"
$SEC"1"
CDS_SEC"1";
"A"
$PN"1"4;
"B"
$PN"2"11;
%"UNIVERSAL_GND"
"1","(-3050,2950)","0","logical_power","I35";
;
HDL_POWER"GND"
CDS_LIB"logical_power";
"A"11;
%"Q_RES"
"2","(-3050,3350)","0","pure_quanta","I36";
;
PART_NUMBER"CS14992FB06"
WATTAGE"1/16W"
VALUE"499"
TOLERANCE"1%"
MATERIAL"CHIP"
PACK_TYPE"0402LF"
LOCATION"PR4229"
BOM_COST"VR_PCH"
CDS_LIB"pure_quanta"
$SEC"1"
CDS_SEC"1";
"A"
$PN"1"4;
"B"
$PN"2"11;
%"VCC15"
"1","(-3050,3700)","0","logical_power","I37";
;
HDL_POWER"PVCCFA_EHV_CPU0"
CDS_LIB"logical_power";
"A"4;
%"VCC15"
"1","(-5475,4825)","0","logical_power","I38";
;
HDL_POWER"SW_P12V_PVCCINFAON_CPU0_FLT"
CDS_LIB"logical_power";
"A"5;
%"UNIVERSAL_GND"
"1","(-10525,3275)","0","logical_power","I5";
;
HDL_POWER"GND"
CDS_LIB"logical_power";
"A"7;
%"Q_RES"
"2","(-10075,5025)","0","pure_quanta","I8";
;
PART_NUMBER"CS00002JB13"
MATERIAL"CHIP"
PACK_TYPE"0402LF"
VALUE"0"
TOLERANCE"5%"
WATTAGE"1/16W"
LOCATION"PR442"
CDS_LIB"pure_quanta"
$SEC"1"
CDS_SEC"1";
"A"
$PN"1"1;
"B"
$PN"2"15;
%"VCC15"
"1","(-10075,5250)","0","logical_power","I9";
;
HDL_POWER"P5V"
CDS_LIB"logical_power";
"A"1;
END.
